FILE_TYPE=LIBRARY_PARTS;
primitive 'LM75BD';
  pin
    'SDA':
      PIN_NUMBER='(1)';
      BIDIRECTIONAL='TRUE';
      INPUT_LOAD='(-0.01,0.01)';
      OUTPUT_LOAD='(1.0,-1.0)';
    'SCL':
      PIN_NUMBER='(2)';
      INPUT_LOAD='(-0.01,0.01)';
    'OS':
      PIN_NUMBER='(3)';
      OUTPUT_LOAD='(1.0,-1.0)';
    'GND':
      PIN_NUMBER='(4)';
      PINUSE='POWER';
      NO_LOAD_CHECK='Both';
      NO_IO_CHECK='Both';
      NO_ASSERT_CHECK='TRUE';
      NO_DIR_CHECK='TRUE';
      ALLOW_CONNECT='TRUE';
    'A2':
      PIN_NUMBER='(5)';
      INPUT_LOAD='(-0.01,0.01)';
    'A1':
      PIN_NUMBER='(6)';
      INPUT_LOAD='(-0.01,0.01)';
    'A0':
      PIN_NUMBER='(7)';
      INPUT_LOAD='(-0.01,0.01)';
    'VCC':
      PIN_NUMBER='(8)';
      PINUSE='POWER';
      NO_LOAD_CHECK='Both';
      NO_IO_CHECK='Both';
      NO_ASSERT_CHECK='TRUE';
      NO_DIR_CHECK='TRUE';
      ALLOW_CONNECT='TRUE';
  end_pin;
  body
    PART_NAME='LM75BD';
    BODY_NAME='LM75BD';
    PHYS_DES_PREFIX='U';
    CLASS='IC';
  end_body;
end_primitive;

END.
